# T6G (Grand Teton) — schematic netlist excerpt (pin names and nets, part order shuffled) for the footprints in the layout excerpt that follows; sources: Cadence DE-HDL packaged netlist, KiCad conversion of 04192023_DAF0TMB3IC0_F0TG_MB_C_brd_V02_OCP.brd

C6737  Q_CAP_DIFFBUS  DIFF BUS_0.22UF 6.3V 20% X6S  pkg C0201  page 352 : \1\ = P5E_CPU1_P3_TX_BUF_C_DP<6> ; \2\ = P5E_CPU1_P3_TX_BUF_DP<6>
PR200  Q_RES  0 5% CHIP  pkg 0402LF  page 212 : A = PVDDCR_CPU0_P1_VOS4 ; B = PVDDCR_CPU0_P1
R2318  Q_RES  0 5% CHIP  pkg 0402LF  page 27 : A = UART_CPU0_SCM_UART1_R_TX ; B = UART_CPU0_SCM_UART1_TX

(kicad_pcb
	(version 20260206)
	(generator "pcbnew")
	(generator_version "10.0")
	(general
		(thickness 1.6)
		(legacy_teardrops no)
	)
	(paper "A4")
	(title_block
		(title "04192023_DAF0TMB3IC0_F0TG_MB_C_brd_V02_OCP.brd")
		(comment 1 "Grand Teton / footprints 5623-5625 of 8354")
	)
	(layers
		(0 "F.Cu" signal "TOP")
		(4 "In1.Cu" signal "GND")
		(6 "In2.Cu" signal "IN1")
		(8 "In3.Cu" signal "GND1")
		(10 "In4.Cu" signal "IN2")
		(12 "In5.Cu" signal "GND2")
		(14 "In6.Cu" signal "IN3")
		(16 "In7.Cu" signal "GND3")
		(18 "In8.Cu" signal "VCC")
		(20 "In9.Cu" signal "VCC1")
		(22 "In10.Cu" signal "GND4")
		(24 "In11.Cu" signal "IN4")
		(26 "In12.Cu" signal "GND5")
		(28 "In13.Cu" signal "IN5")
		(30 "In14.Cu" signal "GND6")
		(32 "In15.Cu" signal "IN6")
		(34 "In16.Cu" signal "GND7")
		(2 "B.Cu" signal "BOTTOM")
		(9 "F.Adhes" user "F.Adhesive")
		(11 "B.Adhes" user "B.Adhesive")
		(13 "F.Paste" user "Package Geometry/Pastemask Top")
		(15 "B.Paste" user "Package Geometry/Pastemask Bottom")
		(5 "F.SilkS" user "Ref Des/Silkscreen Top")
		(7 "B.SilkS" user "Ref Des/Silkscreen Bottom")
		(1 "F.Mask" user "Board Geometry/Soldermask Top")
		(3 "B.Mask" user "Board Geometry/Soldermask Bottom")
		(17 "Dwgs.User" user "User.Drawings")
		(19 "Cmts.User" user "User.Comments")
		(21 "Eco1.User" user "User.Eco1")
		(23 "Eco2.User" user "User.Eco2")
		(25 "Edge.Cuts" user "Board Geometry/Outline")
		(27 "Margin" user)
		(31 "F.CrtYd" user "Package Geometry/Place Bound Top")
		(29 "B.CrtYd" user "Package Geometry/Place Bound Bottom")
		(35 "F.Fab" user "Ref Des/Assembly Top")
		(33 "B.Fab" user "Ref Des/Assembly Bottom")
	)
	(footprint ""
		(layer "B.Cu")
		(at 111.11738 -175.506634 90)
		(property "Reference" "PR200"
			(at 0 0 90)
			(layer "B.SilkS")
			(hide yes)
			(effects
				(font
					(size 1.27 1.27)
				)
				(justify mirror)
			)
		)
		(property "Value" ""
			(at 0 0 90)
			(layer "B.Fab")
			(effects
				(font
					(size 1.27 1.27)
				)
				(justify mirror)
			)
		)
		(duplicate_pad_numbers_are_jumpers no)
		(fp_line
			(start 0.7874 -0.4064)
			(end -0.7874 -0.4064)
			(stroke
				(width 0.1524)
				(type default)
			)
			(layer "B.SilkS")
		)
		(fp_line
			(start -0.7874 -0.4064)
			(end -0.7874 0.4064)
			(stroke
				(width 0.1524)
				(type default)
			)
			(layer "B.SilkS")
		)
		(fp_line
			(start 0.7874 0.4064)
			(end 0.7874 -0.4064)
			(stroke
				(width 0.1524)
				(type default)
			)
			(layer "B.SilkS")
		)
		(fp_line
			(start -0.7874 0.4064)
			(end 0.7874 0.4064)
			(stroke
				(width 0.1524)
				(type default)
			)
			(layer "B.SilkS")
		)
		(fp_line
			(start 0.67945 -0.305054)
			(end 0.12065 -0.305054)
			(stroke
				(width 0.1)
				(type default)
			)
			(layer "B.Fab")
		)
		(fp_line
			(start 0.12065 -0.305054)
			(end 0.12065 -0.2794)
			(stroke
				(width 0.1)
				(type default)
			)
			(layer "B.Fab")
		)
		(fp_line
			(start -0.12065 -0.3048)
			(end -0.67945 -0.3048)
			(stroke
				(width 0.1)
				(type default)
			)
			(layer "B.Fab")
		)
		(fp_line
			(start -0.67945 -0.3048)
			(end -0.67945 0.3048)
			(stroke
				(width 0.1)
				(type default)
			)
			(layer "B.Fab")
		)
		(fp_line
			(start 0.12065 -0.2794)
			(end -0.12065 -0.2794)
			(stroke
				(width 0.1)
				(type default)
			)
			(layer "B.Fab")
		)
		(fp_line
			(start -0.12065 -0.2794)
			(end -0.12065 -0.3048)
			(stroke
				(width 0.1)
				(type default)
			)
			(layer "B.Fab")
		)
		(fp_line
			(start 0.12065 0.2794)
			(end 0.12065 0.3048)
			(stroke
				(width 0.1)
				(type default)
			)
			(layer "B.Fab")
		)
		(fp_line
			(start -0.120396 0.2794)
			(end 0.12065 0.2794)
			(stroke
				(width 0.1)
				(type default)
			)
			(layer "B.Fab")
		)
		(fp_line
			(start 0.67945 0.3048)
			(end 0.67945 -0.305054)
			(stroke
				(width 0.1)
				(type default)
			)
			(layer "B.Fab")
		)
		(fp_line
			(start 0.12065 0.3048)
			(end 0.67945 0.3048)
			(stroke
				(width 0.1)
				(type default)
			)
			(layer "B.Fab")
		)
		(fp_line
			(start -0.120396 0.3048)
			(end -0.120396 0.2794)
			(stroke
				(width 0.1)
				(type default)
			)
			(layer "B.Fab")
		)
		(fp_line
			(start -0.67945 0.3048)
			(end -0.120396 0.3048)
			(stroke
				(width 0.1)
				(type default)
			)
			(layer "B.Fab")
		)
		(pad "1" smd circle
			(at 0.40005 0 270)
			(size 0 0)
			(layers "B.Cu" "B.Mask" "B.Paste")
			(net "PVDDCR_CPU0_P1_VOS4")
		)
		(pad "2" smd circle
			(at -0.40005 0 270)
			(size 0 0)
			(layers "B.Cu" "B.Mask" "B.Paste")
			(net "PVDDCR_CPU0_P1")
		)
	)
	(footprint ""
		(layer "B.Cu")
		(at 135.694166 -408.517344 90)
		(property "Reference" "C6737"
			(at 0 0 90)
			(layer "B.SilkS")
			(hide yes)
			(effects
				(font
					(size 1.27 1.27)
				)
				(justify mirror)
			)
		)
		(property "Value" ""
			(at 0 0 90)
			(layer "B.Fab")
			(effects
				(font
					(size 1.27 1.27)
				)
				(justify mirror)
			)
		)
		(duplicate_pad_numbers_are_jumpers no)
		(fp_line
			(start 0.299974 -0.150114)
			(end -0.299974 -0.150114)
			(stroke
				(width 0.1)
				(type default)
			)
			(layer "B.Fab")
		)
		(fp_line
			(start -0.299974 -0.150114)
			(end -0.299974 0.150114)
			(stroke
				(width 0.1)
				(type default)
			)
			(layer "B.Fab")
		)
		(fp_line
			(start 0.299974 0.150114)
			(end 0.299974 -0.150114)
			(stroke
				(width 0.1)
				(type default)
			)
			(layer "B.Fab")
		)
		(fp_line
			(start -0.299974 0.150114)
			(end 0.299974 0.150114)
			(stroke
				(width 0.1)
				(type default)
			)
			(layer "B.Fab")
		)
		(pad "1" smd rect
			(at 0.2667 0 270)
			(size 0.3048 0.381)
			(layers "B.Cu" "B.Mask" "B.Paste")
			(net "P5E_CPU1_P3_TX_BUF_C_DP<6>")
		)
		(pad "2" smd rect
			(at -0.2667 0 270)
			(size 0.3048 0.381)
			(layers "B.Cu" "B.Mask" "B.Paste")
			(net "P5E_CPU1_P3_TX_BUF_DP<6>")
		)
	)
	(footprint ""
		(layer "B.Cu")
		(at 339.134958 -305.812952)
		(property "Reference" "R2318"
			(at 0 0 0)
			(layer "B.SilkS")
			(hide yes)
			(effects
				(font
					(size 1.27 1.27)
				)
				(justify mirror)
			)
		)
		(property "Value" ""
			(at 0 0 0)
			(layer "B.Fab")
			(effects
				(font
					(size 1.27 1.27)
				)
				(justify mirror)
			)
		)
		(duplicate_pad_numbers_are_jumpers no)
		(fp_line
			(start -0.7874 -0.4064)
			(end -0.7874 0.4064)
			(stroke
				(width 0.1524)
				(type default)
			)
			(layer "B.SilkS")
		)
		(fp_line
			(start -0.7874 0.4064)
			(end 0.7874 0.4064)
			(stroke
				(width 0.1524)
				(type default)
			)
			(layer "B.SilkS")
		)
		(fp_line
			(start 0.7874 -0.4064)
			(end -0.7874 -0.4064)
			(stroke
				(width 0.1524)
				(type default)
			)
			(layer "B.SilkS")
		)
		(fp_line
			(start 0.7874 0.4064)
			(end 0.7874 -0.4064)
			(stroke
				(width 0.1524)
				(type default)
			)
			(layer "B.SilkS")
		)
		(fp_line
			(start -0.67945 -0.3048)
			(end -0.67945 0.3048)
			(stroke
				(width 0.1)
				(type default)
			)
			(layer "B.Fab")
		)
		(fp_line
			(start -0.67945 0.3048)
			(end -0.120396 0.3048)
			(stroke
				(width 0.1)
				(type default)
			)
			(layer "B.Fab")
		)
		(fp_line
			(start -0.12065 -0.3048)
			(end -0.67945 -0.3048)
			(stroke
				(width 0.1)
				(type default)
			)
			(layer "B.Fab")
		)
		(fp_line
			(start -0.12065 -0.2794)
			(end -0.12065 -0.3048)
			(stroke
				(width 0.1)
				(type default)
			)
			(layer "B.Fab")
		)
		(fp_line
			(start -0.120396 0.2794)
			(end 0.12065 0.2794)
			(stroke
				(width 0.1)
				(type default)
			)
			(layer "B.Fab")
		)
		(fp_line
			(start -0.120396 0.3048)
			(end -0.120396 0.2794)
			(stroke
				(width 0.1)
				(type default)
			)
			(layer "B.Fab")
		)
		(fp_line
			(start 0.12065 -0.305054)
			(end 0.12065 -0.2794)
			(stroke
				(width 0.1)
				(type default)
			)
			(layer "B.Fab")
		)
		(fp_line
			(start 0.12065 -0.2794)
			(end -0.12065 -0.2794)
			(stroke
				(width 0.1)
				(type default)
			)
			(layer "B.Fab")
		)
		(fp_line
			(start 0.12065 0.2794)
			(end 0.12065 0.3048)
			(stroke
				(width 0.1)
				(type default)
			)
			(layer "B.Fab")
		)
		(fp_line
			(start 0.12065 0.3048)
			(end 0.67945 0.3048)
			(stroke
				(width 0.1)
				(type default)
			)
			(layer "B.Fab")
		)
		(fp_line
			(start 0.67945 -0.305054)
			(end 0.12065 -0.305054)
			(stroke
				(width 0.1)
				(type default)
			)
			(layer "B.Fab")
		)
		(fp_line
			(start 0.67945 0.3048)
			(end 0.67945 -0.305054)
			(stroke
				(width 0.1)
				(type default)
			)
			(layer "B.Fab")
		)
		(pad "1" smd circle
			(at 0.40005 0 180)
			(size 0 0)
			(layers "B.Cu" "B.Mask" "B.Paste")
			(net "UART_CPU0_SCM_UART1_R_TX")
		)
		(pad "2" smd circle
			(at -0.40005 0 180)
			(size 0 0)
			(layers "B.Cu" "B.Mask" "B.Paste")
			(net "UART_CPU0_SCM_UART1_TX")
		)
	)
)
